(kicad_pcb
	(version 20260206)
	(generator "pcbnew")
	(generator_version "10.0")
	(general
		(thickness 1.6)
		(legacy_teardrops no)
	)
	(paper "A4")
	(title_block
		(title "04192023_DAF0TMB3IC0_F0TG_MB_C_brd_V02_OCP.brd")
		(comment 1 "Grand Teton / footprints 1849-1856 of 8354")
	)
	(layers
		(0 "F.Cu" signal "TOP")
		(4 "In1.Cu" signal "GND")
		(6 "In2.Cu" signal "IN1")
		(8 "In3.Cu" signal "GND1")
		(10 "In4.Cu" signal "IN2")
		(12 "In5.Cu" signal "GND2")
		(14 "In6.Cu" signal "IN3")
		(16 "In7.Cu" signal "GND3")
		(18 "In8.Cu" signal "VCC")
		(20 "In9.Cu" signal "VCC1")
		(22 "In10.Cu" signal "GND4")
		(24 "In11.Cu" signal "IN4")
		(26 "In12.Cu" signal "GND5")
		(28 "In13.Cu" signal "IN5")
		(30 "In14.Cu" signal "GND6")
		(32 "In15.Cu" signal "IN6")
		(34 "In16.Cu" signal "GND7")
		(2 "B.Cu" signal "BOTTOM")
		(9 "F.Adhes" user "F.Adhesive")
		(11 "B.Adhes" user "B.Adhesive")
		(13 "F.Paste" user "Package Geometry/Pastemask Top")
		(15 "B.Paste" user "Package Geometry/Pastemask Bottom")
		(5 "F.SilkS" user "Ref Des/Silkscreen Top")
		(7 "B.SilkS" user "Ref Des/Silkscreen Bottom")
		(1 "F.Mask" user "Board Geometry/Soldermask Top")
		(3 "B.Mask" user "Board Geometry/Soldermask Bottom")
		(17 "Dwgs.User" user "User.Drawings")
		(19 "Cmts.User" user "User.Comments")
		(21 "Eco1.User" user "User.Eco1")
		(23 "Eco2.User" user "User.Eco2")
		(25 "Edge.Cuts" user "Board Geometry/Outline")
		(27 "Margin" user)
		(31 "F.CrtYd" user "Package Geometry/Place Bound Top")
		(29 "B.CrtYd" user "Package Geometry/Place Bound Bottom")
		(35 "F.Fab" user "Ref Des/Assembly Top")
		(33 "B.Fab" user "Ref Des/Assembly Bottom")
	)
	(footprint ""
		(layer "F.Cu")
		(at 70.9676 -382.6764 180)
		(property "Reference" "R6716"
			(at 0 0 180)
			(layer "F.SilkS")
			(hide yes)
			(effects
				(font
					(size 1.27 1.27)
				)
			)
		)
		(property "Value" ""
			(at 0 0 180)
			(layer "F.Fab")
			(effects
				(font
					(size 1.27 1.27)
				)
			)
		)
		(duplicate_pad_numbers_are_jumpers no)
		(fp_line
			(start 0.32512 0.175006)
			(end -0.32512 0.175006)
			(stroke
				(width 0.1)
				(type default)
			)
			(layer "F.Fab")
		)
		(fp_line
			(start 0.32512 -0.175006)
			(end 0.32512 0.175006)
			(stroke
				(width 0.1)
				(type default)
			)
			(layer "F.Fab")
		)
		(fp_line
			(start -0.32512 0.175006)
			(end -0.32512 -0.175006)
			(stroke
				(width 0.1)
				(type default)
			)
			(layer "F.Fab")
		)
		(fp_line
			(start -0.32512 -0.175006)
			(end 0.32512 -0.175006)
			(stroke
				(width 0.1)
				(type default)
			)
			(layer "F.Fab")
		)
		(pad "1" smd rect
			(at -0.2667 0 180)
			(size 0.3048 0.381)
			(layers "F.Cu" "F.Mask" "F.Paste")
			(net "P1V8_CPU1_RT_1D")
		)
		(pad "2" smd rect
			(at 0.2667 0)
			(size 0.3048 0.381)
			(layers "F.Cu" "F.Mask" "F.Paste")
			(net "RT_CPU1_P0_ADDR1")
		)
	)
	(footprint ""
		(layer "F.Cu")
		(at 271.092676 -117.48135)
		(property "Reference" "R6229"
			(at 0 0 0)
			(layer "F.SilkS")
			(hide yes)
			(effects
				(font
					(size 1.27 1.27)
				)
			)
		)
		(property "Value" ""
			(at 0 0 0)
			(layer "F.Fab")
			(effects
				(font
					(size 1.27 1.27)
				)
			)
		)
		(duplicate_pad_numbers_are_jumpers no)
		(fp_line
			(start -0.7874 -0.4064)
			(end 0.7874 -0.4064)
			(stroke
				(width 0.1524)
				(type default)
			)
			(layer "F.SilkS")
		)
		(fp_line
			(start -0.7874 0.4064)
			(end -0.7874 -0.4064)
			(stroke
				(width 0.1524)
				(type default)
			)
			(layer "F.SilkS")
		)
		(fp_line
			(start 0.7874 -0.4064)
			(end 0.7874 0.4064)
			(stroke
				(width 0.1524)
				(type default)
			)
			(layer "F.SilkS")
		)
		(fp_line
			(start 0.7874 0.4064)
			(end -0.7874 0.4064)
			(stroke
				(width 0.1524)
				(type default)
			)
			(layer "F.SilkS")
		)
		(fp_line
			(start -0.67945 -0.305054)
			(end -0.12065 -0.305054)
			(stroke
				(width 0.1)
				(type default)
			)
			(layer "F.Fab")
		)
		(fp_line
			(start -0.67945 0.3048)
			(end -0.67945 -0.305054)
			(stroke
				(width 0.1)
				(type default)
			)
			(layer "F.Fab")
		)
		(fp_line
			(start -0.12065 -0.305054)
			(end -0.12065 -0.2794)
			(stroke
				(width 0.1)
				(type default)
			)
			(layer "F.Fab")
		)
		(fp_line
			(start -0.12065 -0.2794)
			(end 0.12065 -0.2794)
			(stroke
				(width 0.1)
				(type default)
			)
			(layer "F.Fab")
		)
		(fp_line
			(start -0.12065 0.2794)
			(end -0.12065 0.3048)
			(stroke
				(width 0.1)
				(type default)
			)
			(layer "F.Fab")
		)
		(fp_line
			(start -0.12065 0.3048)
			(end -0.67945 0.3048)
			(stroke
				(width 0.1)
				(type default)
			)
			(layer "F.Fab")
		)
		(fp_line
			(start 0.120396 0.2794)
			(end -0.12065 0.2794)
			(stroke
				(width 0.1)
				(type default)
			)
			(layer "F.Fab")
		)
		(fp_line
			(start 0.120396 0.3048)
			(end 0.120396 0.2794)
			(stroke
				(width 0.1)
				(type default)
			)
			(layer "F.Fab")
		)
		(fp_line
			(start 0.12065 -0.3048)
			(end 0.67945 -0.3048)
			(stroke
				(width 0.1)
				(type default)
			)
			(layer "F.Fab")
		)
		(fp_line
			(start 0.12065 -0.2794)
			(end 0.12065 -0.3048)
			(stroke
				(width 0.1)
				(type default)
			)
			(layer "F.Fab")
		)
		(fp_line
			(start 0.67945 -0.3048)
			(end 0.67945 0.3048)
			(stroke
				(width 0.1)
				(type default)
			)
			(layer "F.Fab")
		)
		(fp_line
			(start 0.67945 0.3048)
			(end 0.120396 0.3048)
			(stroke
				(width 0.1)
				(type default)
			)
			(layer "F.Fab")
		)
		(pad "1" smd circle
			(at -0.40005 0)
			(size 0 0)
			(layers "F.Cu" "F.Mask" "F.Paste")
			(net "SMB_P12V_HSC_SCL_R")
		)
		(pad "2" smd circle
			(at 0.40005 0)
			(size 0 0)
			(layers "F.Cu" "F.Mask" "F.Paste")
			(net "SMB_P12V_HSC_SCL")
		)
	)
	(footprint ""
		(layer "F.Cu")
		(at 361.22229 -393.9032 90)
		(property "Reference" "R1015"
			(at 0 0 90)
			(layer "F.SilkS")
			(hide yes)
			(effects
				(font
					(size 1.27 1.27)
				)
			)
		)
		(property "Value" ""
			(at 0 0 90)
			(layer "F.Fab")
			(effects
				(font
					(size 1.27 1.27)
				)
			)
		)
		(duplicate_pad_numbers_are_jumpers no)
		(fp_line
			(start 0.32512 -0.175006)
			(end 0.32512 0.175006)
			(stroke
				(width 0.1)
				(type default)
			)
			(layer "F.Fab")
		)
		(fp_line
			(start -0.32512 -0.175006)
			(end 0.32512 -0.175006)
			(stroke
				(width 0.1)
				(type default)
			)
			(layer "F.Fab")
		)
		(fp_line
			(start 0.32512 0.175006)
			(end -0.32512 0.175006)
			(stroke
				(width 0.1)
				(type default)
			)
			(layer "F.Fab")
		)
		(fp_line
			(start -0.32512 0.175006)
			(end -0.32512 -0.175006)
			(stroke
				(width 0.1)
				(type default)
			)
			(layer "F.Fab")
		)
		(pad "1" smd rect
			(at -0.2667 0 90)
			(size 0.3048 0.381)
			(layers "F.Cu" "F.Mask" "F.Paste")
			(net "P1V8_CPU0_RT_1D")
		)
		(pad "2" smd rect
			(at 0.2667 0 270)
			(size 0.3048 0.381)
			(layers "F.Cu" "F.Mask" "F.Paste")
			(net "RT_CPU0_P1_ADDR2")
		)
	)
	(footprint ""
		(layer "F.Cu")
		(at 141.197838 -168.30167)
		(property "Reference" "TP20"
			(at 1.07442 0.112268 0)
			(unlocked yes)
			(layer "F.SilkS")
			(effects
				(font
					(size 0.7874 0.5842)
					(thickness 0.1524)
				)
				(justify left)
			)
		)
		(property "Value" ""
			(at 0 0 0)
			(layer "F.Fab")
			(effects
				(font
					(size 1.27 1.27)
				)
			)
		)
		(duplicate_pad_numbers_are_jumpers no)
		(pad "1" smd circle
			(at 0 0)
			(size 0.762 0.762)
			(layers "F.Cu" "F.Mask" "F.Paste")
			(net "VSENSE_PVDDCR_SOC_P1_DP")
		)
	)
	(footprint ""
		(layer "F.Cu")
		(at 163.144454 -38.493954 -90)
		(property "Reference" "R2487"
			(at 0 0 270)
			(layer "F.SilkS")
			(hide yes)
			(effects
				(font
					(size 1.27 1.27)
				)
			)
		)
		(property "Value" ""
			(at 0 0 270)
			(layer "F.Fab")
			(effects
				(font
					(size 1.27 1.27)
				)
			)
		)
		(duplicate_pad_numbers_are_jumpers no)
		(fp_line
			(start -0.7874 0.4064)
			(end -0.7874 -0.4064)
			(stroke
				(width 0.1524)
				(type default)
			)
			(layer "F.SilkS")
		)
		(fp_line
			(start 0.7874 0.4064)
			(end -0.7874 0.4064)
			(stroke
				(width 0.1524)
				(type default)
			)
			(layer "F.SilkS")
		)
		(fp_line
			(start -0.7874 -0.4064)
			(end 0.7874 -0.4064)
			(stroke
				(width 0.1524)
				(type default)
			)
			(layer "F.SilkS")
		)
		(fp_line
			(start 0.7874 -0.4064)
			(end 0.7874 0.4064)
			(stroke
				(width 0.1524)
				(type default)
			)
			(layer "F.SilkS")
		)
		(fp_line
			(start -0.67945 0.3048)
			(end -0.67945 -0.305054)
			(stroke
				(width 0.1)
				(type default)
			)
			(layer "F.Fab")
		)
		(fp_line
			(start -0.12065 0.3048)
			(end -0.67945 0.3048)
			(stroke
				(width 0.1)
				(type default)
			)
			(layer "F.Fab")
		)
		(fp_line
			(start 0.120396 0.3048)
			(end 0.120396 0.2794)
			(stroke
				(width 0.1)
				(type default)
			)
			(layer "F.Fab")
		)
		(fp_line
			(start 0.67945 0.3048)
			(end 0.120396 0.3048)
			(stroke
				(width 0.1)
				(type default)
			)
			(layer "F.Fab")
		)
		(fp_line
			(start -0.12065 0.2794)
			(end -0.12065 0.3048)
			(stroke
				(width 0.1)
				(type default)
			)
			(layer "F.Fab")
		)
		(fp_line
			(start 0.120396 0.2794)
			(end -0.12065 0.2794)
			(stroke
				(width 0.1)
				(type default)
			)
			(layer "F.Fab")
		)
		(fp_line
			(start -0.12065 -0.2794)
			(end 0.12065 -0.2794)
			(stroke
				(width 0.1)
				(type default)
			)
			(layer "F.Fab")
		)
		(fp_line
			(start 0.12065 -0.2794)
			(end 0.12065 -0.3048)
			(stroke
				(width 0.1)
				(type default)
			)
			(layer "F.Fab")
		)
		(fp_line
			(start 0.12065 -0.3048)
			(end 0.67945 -0.3048)
			(stroke
				(width 0.1)
				(type default)
			)
			(layer "F.Fab")
		)
		(fp_line
			(start 0.67945 -0.3048)
			(end 0.67945 0.3048)
			(stroke
				(width 0.1)
				(type default)
			)
			(layer "F.Fab")
		)
		(fp_line
			(start -0.67945 -0.305054)
			(end -0.12065 -0.305054)
			(stroke
				(width 0.1)
				(type default)
			)
			(layer "F.Fab")
		)
		(fp_line
			(start -0.12065 -0.305054)
			(end -0.12065 -0.2794)
			(stroke
				(width 0.1)
				(type default)
			)
			(layer "F.Fab")
		)
		(pad "1" smd circle
			(at -0.40005 0 270)
			(size 0 0)
			(layers "F.Cu" "F.Mask" "F.Paste")
			(net "P3V3_AUX")
		)
		(pad "2" smd circle
			(at 0.40005 0 270)
			(size 0 0)
			(layers "F.Cu" "F.Mask" "F.Paste")
			(net "IRQ_LVC3_WAKE_BUF_N")
		)
	)
	(footprint ""
		(layer "F.Cu")
		(at 22.479 -367.919)
		(property "Reference" "R1494"
			(at 0 0 0)
			(layer "F.SilkS")
			(hide yes)
			(effects
				(font
					(size 1.27 1.27)
				)
			)
		)
		(property "Value" ""
			(at 0 0 0)
			(layer "F.Fab")
			(effects
				(font
					(size 1.27 1.27)
				)
			)
		)
		(duplicate_pad_numbers_are_jumpers no)
		(fp_line
			(start -0.7874 -0.4064)
			(end 0.7874 -0.4064)
			(stroke
				(width 0.1524)
				(type default)
			)
			(layer "F.SilkS")
		)
		(fp_line
			(start -0.7874 0.4064)
			(end -0.7874 -0.4064)
			(stroke
				(width 0.1524)
				(type default)
			)
			(layer "F.SilkS")
		)
		(fp_line
			(start 0.7874 -0.4064)
			(end 0.7874 0.4064)
			(stroke
				(width 0.1524)
				(type default)
			)
			(layer "F.SilkS")
		)
		(fp_line
			(start 0.7874 0.4064)
			(end -0.7874 0.4064)
			(stroke
				(width 0.1524)
				(type default)
			)
			(layer "F.SilkS")
		)
		(fp_line
			(start -0.67945 -0.305054)
			(end -0.12065 -0.305054)
			(stroke
				(width 0.1)
				(type default)
			)
			(layer "F.Fab")
		)
		(fp_line
			(start -0.67945 0.3048)
			(end -0.67945 -0.305054)
			(stroke
				(width 0.1)
				(type default)
			)
			(layer "F.Fab")
		)
		(fp_line
			(start -0.12065 -0.305054)
			(end -0.12065 -0.2794)
			(stroke
				(width 0.1)
				(type default)
			)
			(layer "F.Fab")
		)
		(fp_line
			(start -0.12065 -0.2794)
			(end 0.12065 -0.2794)
			(stroke
				(width 0.1)
				(type default)
			)
			(layer "F.Fab")
		)
		(fp_line
			(start -0.12065 0.2794)
			(end -0.12065 0.3048)
			(stroke
				(width 0.1)
				(type default)
			)
			(layer "F.Fab")
		)
		(fp_line
			(start -0.12065 0.3048)
			(end -0.67945 0.3048)
			(stroke
				(width 0.1)
				(type default)
			)
			(layer "F.Fab")
		)
		(fp_line
			(start 0.120396 0.2794)
			(end -0.12065 0.2794)
			(stroke
				(width 0.1)
				(type default)
			)
			(layer "F.Fab")
		)
		(fp_line
			(start 0.120396 0.3048)
			(end 0.120396 0.2794)
			(stroke
				(width 0.1)
				(type default)
			)
			(layer "F.Fab")
		)
		(fp_line
			(start 0.12065 -0.3048)
			(end 0.67945 -0.3048)
			(stroke
				(width 0.1)
				(type default)
			)
			(layer "F.Fab")
		)
		(fp_line
			(start 0.12065 -0.2794)
			(end 0.12065 -0.3048)
			(stroke
				(width 0.1)
				(type default)
			)
			(layer "F.Fab")
		)
		(fp_line
			(start 0.67945 -0.3048)
			(end 0.67945 0.3048)
			(stroke
				(width 0.1)
				(type default)
			)
			(layer "F.Fab")
		)
		(fp_line
			(start 0.67945 0.3048)
			(end 0.120396 0.3048)
			(stroke
				(width 0.1)
				(type default)
			)
			(layer "F.Fab")
		)
		(pad "1" smd circle
			(at -0.40005 0)
			(size 0 0)
			(layers "F.Cu" "F.Mask" "F.Paste")
			(net "SMB_VR_3V3STBY_SDA")
		)
		(pad "2" smd circle
			(at 0.40005 0)
			(size 0 0)
			(layers "F.Cu" "F.Mask" "F.Paste")
			(net "SMB_SCM_2_R1_SDA")
		)
	)
	(footprint ""
		(layer "F.Cu")
		(at 468.950294 -43.252898 180)
		(property "Reference" "R561"
			(at 0 0 180)
			(layer "F.SilkS")
			(hide yes)
			(effects
				(font
					(size 1.27 1.27)
				)
			)
		)
		(property "Value" ""
			(at 0 0 180)
			(layer "F.Fab")
			(effects
				(font
					(size 1.27 1.27)
				)
			)
		)
		(duplicate_pad_numbers_are_jumpers no)
		(fp_line
			(start 0.7874 0.4064)
			(end -0.7874 0.4064)
			(stroke
				(width 0.1524)
				(type default)
			)
			(layer "F.SilkS")
		)
		(fp_line
			(start 0.7874 -0.4064)
			(end 0.7874 0.4064)
			(stroke
				(width 0.1524)
				(type default)
			)
			(layer "F.SilkS")
		)
		(fp_line
			(start -0.7874 0.4064)
			(end -0.7874 -0.4064)
			(stroke
				(width 0.1524)
				(type default)
			)
			(layer "F.SilkS")
		)
		(fp_line
			(start -0.7874 -0.4064)
			(end 0.7874 -0.4064)
			(stroke
				(width 0.1524)
				(type default)
			)
			(layer "F.SilkS")
		)
		(fp_line
			(start 0.67945 0.3048)
			(end 0.120396 0.3048)
			(stroke
				(width 0.1)
				(type default)
			)
			(layer "F.Fab")
		)
		(fp_line
			(start 0.67945 -0.3048)
			(end 0.67945 0.3048)
			(stroke
				(width 0.1)
				(type default)
			)
			(layer "F.Fab")
		)
		(fp_line
			(start 0.12065 -0.2794)
			(end 0.12065 -0.3048)
			(stroke
				(width 0.1)
				(type default)
			)
			(layer "F.Fab")
		)
		(fp_line
			(start 0.12065 -0.3048)
			(end 0.67945 -0.3048)
			(stroke
				(width 0.1)
				(type default)
			)
			(layer "F.Fab")
		)
		(fp_line
			(start 0.120396 0.3048)
			(end 0.120396 0.2794)
			(stroke
				(width 0.1)
				(type default)
			)
			(layer "F.Fab")
		)
		(fp_line
			(start 0.120396 0.2794)
			(end -0.12065 0.2794)
			(stroke
				(width 0.1)
				(type default)
			)
			(layer "F.Fab")
		)
		(fp_line
			(start -0.12065 0.3048)
			(end -0.67945 0.3048)
			(stroke
				(width 0.1)
				(type default)
			)
			(layer "F.Fab")
		)
		(fp_line
			(start -0.12065 0.2794)
			(end -0.12065 0.3048)
			(stroke
				(width 0.1)
				(type default)
			)
			(layer "F.Fab")
		)
		(fp_line
			(start -0.12065 -0.2794)
			(end 0.12065 -0.2794)
			(stroke
				(width 0.1)
				(type default)
			)
			(layer "F.Fab")
		)
		(fp_line
			(start -0.12065 -0.305054)
			(end -0.12065 -0.2794)
			(stroke
				(width 0.1)
				(type default)
			)
			(layer "F.Fab")
		)
		(fp_line
			(start -0.67945 0.3048)
			(end -0.67945 -0.305054)
			(stroke
				(width 0.1)
				(type default)
			)
			(layer "F.Fab")
		)
		(fp_line
			(start -0.67945 -0.305054)
			(end -0.12065 -0.305054)
			(stroke
				(width 0.1)
				(type default)
			)
			(layer "F.Fab")
		)
		(pad "1" smd circle
			(at -0.40005 0 180)
			(size 0 0)
			(layers "F.Cu" "F.Mask" "F.Paste")
			(net "P12V_OCP_SFF_BUF_EN_R")
		)
		(pad "2" smd circle
			(at 0.40005 0 180)
			(size 0 0)
			(layers "F.Cu" "F.Mask" "F.Paste")
			(net "P12V_OCP_EN_1_R")
		)
	)
	(footprint ""
		(layer "F.Cu")
		(at 372.937278 -140.456158)
		(property "Reference" "R8312"
			(at 0 0 0)
			(layer "F.SilkS")
			(hide yes)
			(effects
				(font
					(size 1.27 1.27)
				)
			)
		)
		(property "Value" ""
			(at 0 0 0)
			(layer "F.Fab")
			(effects
				(font
					(size 1.27 1.27)
				)
			)
		)
		(duplicate_pad_numbers_are_jumpers no)
		(fp_line
			(start -0.7874 -0.4064)
			(end 0.7874 -0.4064)
			(stroke
				(width 0.1524)
				(type default)
			)
			(layer "F.SilkS")
		)
		(fp_line
			(start -0.7874 0.4064)
			(end -0.7874 -0.4064)
			(stroke
				(width 0.1524)
				(type default)
			)
			(layer "F.SilkS")
		)
		(fp_line
			(start 0.7874 -0.4064)
			(end 0.7874 0.4064)
			(stroke
				(width 0.1524)
				(type default)
			)
			(layer "F.SilkS")
		)
		(fp_line
			(start 0.7874 0.4064)
			(end -0.7874 0.4064)
			(stroke
				(width 0.1524)
				(type default)
			)
			(layer "F.SilkS")
		)
		(fp_line
			(start -0.67945 -0.305054)
			(end -0.12065 -0.305054)
			(stroke
				(width 0.1)
				(type default)
			)
			(layer "F.Fab")
		)
		(fp_line
			(start -0.67945 0.3048)
			(end -0.67945 -0.305054)
			(stroke
				(width 0.1)
				(type default)
			)
			(layer "F.Fab")
		)
		(fp_line
			(start -0.12065 -0.305054)
			(end -0.12065 -0.2794)
			(stroke
				(width 0.1)
				(type default)
			)
			(layer "F.Fab")
		)
		(fp_line
			(start -0.12065 -0.2794)
			(end 0.12065 -0.2794)
			(stroke
				(width 0.1)
				(type default)
			)
			(layer "F.Fab")
		)
		(fp_line
			(start -0.12065 0.2794)
			(end -0.12065 0.3048)
			(stroke
				(width 0.1)
				(type default)
			)
			(layer "F.Fab")
		)
		(fp_line
			(start -0.12065 0.3048)
			(end -0.67945 0.3048)
			(stroke
				(width 0.1)
				(type default)
			)
			(layer "F.Fab")
		)
		(fp_line
			(start 0.120396 0.2794)
			(end -0.12065 0.2794)
			(stroke
				(width 0.1)
				(type default)
			)
			(layer "F.Fab")
		)
		(fp_line
			(start 0.120396 0.3048)
			(end 0.120396 0.2794)
			(stroke
				(width 0.1)
				(type default)
			)
			(layer "F.Fab")
		)
		(fp_line
			(start 0.12065 -0.3048)
			(end 0.67945 -0.3048)
			(stroke
				(width 0.1)
				(type default)
			)
			(layer "F.Fab")
		)
		(fp_line
			(start 0.12065 -0.2794)
			(end 0.12065 -0.3048)
			(stroke
				(width 0.1)
				(type default)
			)
			(layer "F.Fab")
		)
		(fp_line
			(start 0.67945 -0.3048)
			(end 0.67945 0.3048)
			(stroke
				(width 0.1)
				(type default)
			)
			(layer "F.Fab")
		)
		(fp_line
			(start 0.67945 0.3048)
			(end 0.120396 0.3048)
			(stroke
				(width 0.1)
				(type default)
			)
			(layer "F.Fab")
		)
		(pad "1" smd circle
			(at -0.40005 0)
			(size 0 0)
			(layers "F.Cu" "F.Mask" "F.Paste")
			(net "PVDDCR_CPU0_P0_EN")
		)
		(pad "2" smd circle
			(at 0.40005 0)
			(size 0 0)
			(layers "F.Cu" "F.Mask" "F.Paste")
			(net "PVDDCR_CPU0_P0_EN_R")
		)
	)
)
